(kicad_pcb
	(version 20260206)
	(generator "pcbnew")
	(generator_version "10.0")
	(general
		(thickness 1.6)
		(legacy_teardrops no)
	)
	(paper "A4")
	(title_block
		(title "03242023_DA0F0TMBIJ0_F0T_Motherboard_J_brd_V01_OCP.brd")
		(comment 1 "Grand Teton / footprints 1598-1603 of 6105")
	)
	(layers
		(0 "F.Cu" signal "TOP")
		(4 "In1.Cu" signal "GND")
		(6 "In2.Cu" signal "IN1")
		(8 "In3.Cu" signal "GND1")
		(10 "In4.Cu" signal "IN2")
		(12 "In5.Cu" signal "GND2")
		(14 "In6.Cu" signal "IN3")
		(16 "In7.Cu" signal "GND3")
		(18 "In8.Cu" signal "VCC")
		(20 "In9.Cu" signal "VCC1")
		(22 "In10.Cu" signal "GND4")
		(24 "In11.Cu" signal "IN4")
		(26 "In12.Cu" signal "GND5")
		(28 "In13.Cu" signal "IN5")
		(30 "In14.Cu" signal "GND6")
		(32 "In15.Cu" signal "IN6")
		(34 "In16.Cu" signal "GND7")
		(2 "B.Cu" signal "BOTTOM")
		(9 "F.Adhes" user "F.Adhesive")
		(11 "B.Adhes" user "B.Adhesive")
		(13 "F.Paste" user "Package Geometry/Pastemask Top")
		(15 "B.Paste" user "Package Geometry/Pastemask Bottom")
		(5 "F.SilkS" user "Ref Des/Silkscreen Top")
		(7 "B.SilkS" user "Ref Des/Silkscreen Bottom")
		(1 "F.Mask" user "Board Geometry/Soldermask Top")
		(3 "B.Mask" user "Board Geometry/Soldermask Bottom")
		(17 "Dwgs.User" user "User.Drawings")
		(19 "Cmts.User" user "User.Comments")
		(21 "Eco1.User" user "User.Eco1")
		(23 "Eco2.User" user "User.Eco2")
		(25 "Edge.Cuts" user "Board Geometry/Outline")
		(27 "Margin" user)
		(31 "F.CrtYd" user "Package Geometry/Place Bound Top")
		(29 "B.CrtYd" user "Package Geometry/Place Bound Bottom")
		(35 "F.Fab" user "Ref Des/Assembly Top")
		(33 "B.Fab" user "Ref Des/Assembly Bottom")
	)
	(footprint ""
		(layer "F.Cu")
		(at 116.41328 -417.393628)
		(property "Reference" "U196"
			(at -2.4765 -2.74447 0)
			(unlocked yes)
			(layer "F.SilkS")
			(effects
				(font
					(size 0.7874 0.5842)
					(thickness 0.1524)
				)
				(justify left)
			)
		)
		(property "Value" ""
			(at 0 0 0)
			(layer "F.Fab")
			(effects
				(font
					(size 1.27 1.27)
				)
			)
		)
		(duplicate_pad_numbers_are_jumpers no)
		(fp_line
			(start -1.3462 -1.100074)
			(end -0.670052 -1.100074)
			(stroke
				(width 0.1524)
				(type default)
			)
			(layer "F.SilkS")
		)
		(fp_line
			(start -1.3462 1.100074)
			(end -1.3462 -1.100074)
			(stroke
				(width 0.1524)
				(type default)
			)
			(layer "F.SilkS")
		)
		(fp_line
			(start -0.670052 -1.100074)
			(end 0 -0.381)
			(stroke
				(width 0.1524)
				(type default)
			)
			(layer "F.SilkS")
		)
		(fp_line
			(start 0 -0.381)
			(end 0.670052 -1.100074)
			(stroke
				(width 0.1524)
				(type default)
			)
			(layer "F.SilkS")
		)
		(fp_line
			(start 0.670052 -1.100074)
			(end 1.3462 -1.100074)
			(stroke
				(width 0.1524)
				(type default)
			)
			(layer "F.SilkS")
		)
		(fp_line
			(start 1.3462 -1.100074)
			(end 1.3462 1.100074)
			(stroke
				(width 0.1524)
				(type default)
			)
			(layer "F.SilkS")
		)
		(fp_line
			(start 1.3462 1.100074)
			(end -1.3462 1.100074)
			(stroke
				(width 0.1524)
				(type default)
			)
			(layer "F.SilkS")
		)
		(fp_poly
			(pts
				(xy -0.990854 -1.28016) (xy -1.371854 -2.04216) (xy -0.609854 -2.04216)
			)
			(stroke
				(width 0)
				(type default)
			)
			(fill yes)
			(layer "F.SilkS")
		)
		(fp_line
			(start -1.100074 -0.8001)
			(end -0.670052 -0.8001)
			(stroke
				(width 0.1)
				(type default)
			)
			(layer "F.Fab")
		)
		(fp_line
			(start -1.100074 0.8001)
			(end -1.100074 -0.8001)
			(stroke
				(width 0.1)
				(type default)
			)
			(layer "F.Fab")
		)
		(fp_line
			(start -0.670052 -1.100074)
			(end 0.670052 -1.100074)
			(stroke
				(width 0.1)
				(type default)
			)
			(layer "F.Fab")
		)
		(fp_line
			(start -0.670052 -0.8001)
			(end -0.670052 -1.100074)
			(stroke
				(width 0.1)
				(type default)
			)
			(layer "F.Fab")
		)
		(fp_line
			(start -0.670052 0.8001)
			(end -1.100074 0.8001)
			(stroke
				(width 0.1)
				(type default)
			)
			(layer "F.Fab")
		)
		(fp_line
			(start -0.670052 0.8001)
			(end -0.670052 -0.8001)
			(stroke
				(width 0.1)
				(type default)
			)
			(layer "F.Fab")
		)
		(fp_line
			(start -0.670052 1.100074)
			(end -0.670052 0.8001)
			(stroke
				(width 0.1)
				(type default)
			)
			(layer "F.Fab")
		)
		(fp_line
			(start 0.670052 -1.100074)
			(end 0.670052 -0.8001)
			(stroke
				(width 0.1)
				(type default)
			)
			(layer "F.Fab")
		)
		(fp_line
			(start 0.670052 -0.8001)
			(end 0.670052 0.8001)
			(stroke
				(width 0.1)
				(type default)
			)
			(layer "F.Fab")
		)
		(fp_line
			(start 0.670052 -0.8001)
			(end 1.100074 -0.8001)
			(stroke
				(width 0.1)
				(type default)
			)
			(layer "F.Fab")
		)
		(fp_line
			(start 0.670052 0.8001)
			(end 0.670052 1.100074)
			(stroke
				(width 0.1)
				(type default)
			)
			(layer "F.Fab")
		)
		(fp_line
			(start 0.670052 1.100074)
			(end -0.670052 1.100074)
			(stroke
				(width 0.1)
				(type default)
			)
			(layer "F.Fab")
		)
		(fp_line
			(start 1.100074 -0.8001)
			(end 1.100074 0.8001)
			(stroke
				(width 0.1)
				(type default)
			)
			(layer "F.Fab")
		)
		(fp_line
			(start 1.100074 0.8001)
			(end 0.670052 0.8001)
			(stroke
				(width 0.1)
				(type default)
			)
			(layer "F.Fab")
		)
		(fp_poly
			(pts
				(xy -1.524 -0.649986) (xy -2.286 -1.030986) (xy -2.286 -0.268986)
			)
			(stroke
				(width 0)
				(type default)
			)
			(fill yes)
			(layer "F.Fab")
		)
		(pad "1" smd rect
			(at -0.94996 -0.649986 270)
			(size 0.4064 0.508)
			(layers "F.Cu" "F.Mask" "F.Paste")
			(net "FM_GPU_PWR_EN_R")
		)
		(pad "2" smd rect
			(at -0.94996 0 270)
			(size 0.4064 0.508)
			(layers "F.Cu" "F.Mask" "F.Paste")
			(net "GND")
		)
		(pad "3" smd rect
			(at -0.94996 0.649986 270)
			(size 0.4064 0.508)
			(layers "F.Cu" "F.Mask" "F.Paste")
			(net "GPU_FPGA_RST_R_N")
		)
		(pad "4" smd rect
			(at 0.94996 0.649986 270)
			(size 0.4064 0.508)
			(layers "F.Cu" "F.Mask" "F.Paste")
			(net "GPU_FPGA_RST_R1_BUF_N")
		)
		(pad "5" smd rect
			(at 0.94996 0 270)
			(size 0.4064 0.508)
			(layers "F.Cu" "F.Mask" "F.Paste")
			(net "P3V3_AUX")
		)
		(pad "6" smd rect
			(at 0.94996 -0.649986 270)
			(size 0.4064 0.508)
			(layers "F.Cu" "F.Mask" "F.Paste")
			(net "FM_GPU_PWR_EN_R1")
		)
	)
	(footprint ""
		(layer "F.Cu")
		(at 457.0349 -51.976528)
		(property "Reference" "PC1867"
			(at 0 0 0)
			(layer "F.SilkS")
			(hide yes)
			(effects
				(font
					(size 1.27 1.27)
				)
			)
		)
		(property "Value" ""
			(at 0 0 0)
			(layer "F.Fab")
			(effects
				(font
					(size 1.27 1.27)
				)
			)
		)
		(duplicate_pad_numbers_are_jumpers no)
		(fp_line
			(start -3.400044 1.249934)
			(end 3.400044 1.249934)
			(stroke
				(width 0.1524)
				(type default)
			)
			(layer "F.SilkS")
		)
		(fp_circle
			(center 0 1.249934)
			(end 3.400044 1.249934)
			(stroke
				(width 0.1524)
				(type default)
			)
			(fill no)
			(layer "F.SilkS")
		)
		(fp_poly
			(pts
				(arc
					(start 3.400044 1.249934)
					(mid 0 4.649978)
					(end -3.400044 1.249934)
				)
			)
			(stroke
				(width 0)
				(type default)
			)
			(fill yes)
			(layer "F.SilkS")
		)
		(fp_circle
			(center 0 1.249934)
			(end 3.400044 1.249934)
			(stroke
				(width 0.1)
				(type default)
			)
			(fill no)
			(layer "F.Fab")
		)
		(pad "1" thru_hole rect
			(at 0 0)
			(size 1.524 1.524)
			(drill 1.016)
			(layers "*.Cu" "*.Mask")
			(remove_unused_layers no)
			(net "P3V3_AUX")
			(clearance 0)
			(padstack
				(mode front_inner_back)
				(layer "Inner"
					(shape circle)
					(size 1.524 1.524)
					(clearance 0)
				)
				(layer "B.Cu"
					(shape rect)
					(size 1.524 1.524)
					(clearance 0)
				)
			)
		)
		(pad "2" thru_hole circle
			(at 0 2.500122)
			(size 1.524 1.524)
			(drill 1.016)
			(layers "*.Cu" "*.Mask")
			(remove_unused_layers no)
			(net "GND")
			(clearance 0)
		)
	)
	(footprint ""
		(layer "F.Cu")
		(at 212.299296 -120.457214 180)
		(property "Reference" "U332"
			(at 1.352296 -1.992884 0)
			(unlocked yes)
			(layer "F.SilkS")
			(effects
				(font
					(size 0.7874 0.5842)
					(thickness 0.1524)
				)
				(justify left)
			)
		)
		(property "Value" ""
			(at 0 0 180)
			(layer "F.Fab")
			(effects
				(font
					(size 1.27 1.27)
				)
			)
		)
		(duplicate_pad_numbers_are_jumpers no)
		(fp_line
			(start 1.38176 1.100074)
			(end 1.38176 -1.100074)
			(stroke
				(width 0.1524)
				(type default)
			)
			(layer "F.SilkS")
		)
		(fp_line
			(start 1.38176 -1.100074)
			(end 0.592074 -1.100074)
			(stroke
				(width 0.1524)
				(type default)
			)
			(layer "F.SilkS")
		)
		(fp_line
			(start 0.592074 -1.100074)
			(end 0 -0.508)
			(stroke
				(width 0.1524)
				(type default)
			)
			(layer "F.SilkS")
		)
		(fp_line
			(start 0 -0.508)
			(end -0.592074 -1.100074)
			(stroke
				(width 0.1524)
				(type default)
			)
			(layer "F.SilkS")
		)
		(fp_line
			(start -0.592074 -1.100074)
			(end -1.38176 -1.100074)
			(stroke
				(width 0.1524)
				(type default)
			)
			(layer "F.SilkS")
		)
		(fp_line
			(start -1.38176 1.100074)
			(end 1.38176 1.100074)
			(stroke
				(width 0.1524)
				(type default)
			)
			(layer "F.SilkS")
		)
		(fp_line
			(start -1.38176 -1.100074)
			(end -1.38176 1.100074)
			(stroke
				(width 0.1524)
				(type default)
			)
			(layer "F.SilkS")
		)
		(fp_poly
			(pts
				(xy -1.9431 -0.870204) (xy -1.50241 -0.649986) (xy -1.9431 -0.429768)
			)
			(stroke
				(width 0)
				(type default)
			)
			(fill yes)
			(layer "F.SilkS")
		)
		(fp_line
			(start 0.674878 1.100074)
			(end 0.674878 -1.100074)
			(stroke
				(width 0.1)
				(type default)
			)
			(layer "F.Fab")
		)
		(fp_line
			(start 0.674878 -1.100074)
			(end -0.674878 -1.100074)
			(stroke
				(width 0.1)
				(type default)
			)
			(layer "F.Fab")
		)
		(fp_line
			(start -0.674878 1.100074)
			(end 0.674878 1.100074)
			(stroke
				(width 0.1)
				(type default)
			)
			(layer "F.Fab")
		)
		(fp_line
			(start -0.674878 -1.100074)
			(end -0.674878 1.100074)
			(stroke
				(width 0.1)
				(type default)
			)
			(layer "F.Fab")
		)
		(fp_poly
			(pts
				(xy -1.9431 -0.870204) (xy -1.50241 -0.649986) (xy -1.9431 -0.429768)
			)
			(stroke
				(width 0)
				(type default)
			)
			(fill yes)
			(layer "F.Fab")
		)
		(pad "1" smd rect
			(at -0.94996 -0.649986 90)
			(size 0.4318 0.6096)
			(layers "F.Cu" "F.Mask" "F.Paste")
			(net "FM_AC_PWR_BTN_PLD_N")
		)
		(pad "2" smd rect
			(at -0.94996 0 90)
			(size 0.4318 0.6096)
			(layers "F.Cu" "F.Mask" "F.Paste")
			(net "GND")
		)
		(pad "3" smd rect
			(at -0.94996 0.649986 90)
			(size 0.4318 0.6096)
			(layers "F.Cu" "F.Mask" "F.Paste")
			(net "GND")
		)
		(pad "4" smd rect
			(at 0.94996 0.649986 90)
			(size 0.4318 0.6096)
			(layers "F.Cu" "F.Mask" "F.Paste")
			(net "NC_UXX_2Y")
		)
		(pad "5" smd rect
			(at 0.94996 0 90)
			(size 0.4318 0.6096)
			(layers "F.Cu" "F.Mask" "F.Paste")
			(net "P3V3_AUX")
		)
		(pad "6" smd rect
			(at 0.94996 -0.649986 90)
			(size 0.4318 0.6096)
			(layers "F.Cu" "F.Mask" "F.Paste")
			(net "FM_AC_PWR_BTN_PLD_ISO_R_N")
		)
	)
	(footprint ""
		(layer "F.Cu")
		(at 365.2012 -413.6898 180)
		(property "Reference" "R4801"
			(at 0 0 180)
			(layer "F.SilkS")
			(hide yes)
			(effects
				(font
					(size 1.27 1.27)
				)
			)
		)
		(property "Value" ""
			(at 0 0 180)
			(layer "F.Fab")
			(effects
				(font
					(size 1.27 1.27)
				)
			)
		)
		(duplicate_pad_numbers_are_jumpers no)
		(fp_line
			(start 0.7874 0.4064)
			(end -0.7874 0.4064)
			(stroke
				(width 0.1524)
				(type default)
			)
			(layer "F.SilkS")
		)
		(fp_line
			(start 0.7874 -0.4064)
			(end 0.7874 0.4064)
			(stroke
				(width 0.1524)
				(type default)
			)
			(layer "F.SilkS")
		)
		(fp_line
			(start -0.7874 0.4064)
			(end -0.7874 -0.4064)
			(stroke
				(width 0.1524)
				(type default)
			)
			(layer "F.SilkS")
		)
		(fp_line
			(start -0.7874 -0.4064)
			(end 0.7874 -0.4064)
			(stroke
				(width 0.1524)
				(type default)
			)
			(layer "F.SilkS")
		)
		(fp_line
			(start 0.67945 0.3048)
			(end 0.120396 0.3048)
			(stroke
				(width 0.1)
				(type default)
			)
			(layer "F.Fab")
		)
		(fp_line
			(start 0.67945 -0.3048)
			(end 0.67945 0.3048)
			(stroke
				(width 0.1)
				(type default)
			)
			(layer "F.Fab")
		)
		(fp_line
			(start 0.12065 -0.2794)
			(end 0.12065 -0.3048)
			(stroke
				(width 0.1)
				(type default)
			)
			(layer "F.Fab")
		)
		(fp_line
			(start 0.12065 -0.3048)
			(end 0.67945 -0.3048)
			(stroke
				(width 0.1)
				(type default)
			)
			(layer "F.Fab")
		)
		(fp_line
			(start 0.120396 0.3048)
			(end 0.120396 0.2794)
			(stroke
				(width 0.1)
				(type default)
			)
			(layer "F.Fab")
		)
		(fp_line
			(start 0.120396 0.2794)
			(end -0.12065 0.2794)
			(stroke
				(width 0.1)
				(type default)
			)
			(layer "F.Fab")
		)
		(fp_line
			(start -0.12065 0.3048)
			(end -0.67945 0.3048)
			(stroke
				(width 0.1)
				(type default)
			)
			(layer "F.Fab")
		)
		(fp_line
			(start -0.12065 0.2794)
			(end -0.12065 0.3048)
			(stroke
				(width 0.1)
				(type default)
			)
			(layer "F.Fab")
		)
		(fp_line
			(start -0.12065 -0.2794)
			(end 0.12065 -0.2794)
			(stroke
				(width 0.1)
				(type default)
			)
			(layer "F.Fab")
		)
		(fp_line
			(start -0.12065 -0.305054)
			(end -0.12065 -0.2794)
			(stroke
				(width 0.1)
				(type default)
			)
			(layer "F.Fab")
		)
		(fp_line
			(start -0.67945 0.3048)
			(end -0.67945 -0.305054)
			(stroke
				(width 0.1)
				(type default)
			)
			(layer "F.Fab")
		)
		(fp_line
			(start -0.67945 -0.305054)
			(end -0.12065 -0.305054)
			(stroke
				(width 0.1)
				(type default)
			)
			(layer "F.Fab")
		)
		(pad "1" smd circle
			(at -0.40005 0 180)
			(size 0 0)
			(layers "F.Cu" "F.Mask" "F.Paste")
			(net "P3V3_AUX")
		)
		(pad "2" smd circle
			(at 0.40005 0 180)
			(size 0 0)
			(layers "F.Cu" "F.Mask" "F.Paste")
			(net "PRSNT_CABLE_GPU_A3_ISO_N")
		)
	)
	(footprint ""
		(layer "F.Cu")
		(at 192.601342 -433.96916 -90)
		(property "Reference" "U278"
			(at 1.21412 -2.605532 90)
			(unlocked yes)
			(layer "F.SilkS")
			(effects
				(font
					(size 0.7874 0.5842)
					(thickness 0.1524)
				)
				(justify left)
			)
		)
		(property "Value" ""
			(at 0 0 270)
			(layer "F.Fab")
			(effects
				(font
					(size 1.27 1.27)
				)
			)
		)
		(duplicate_pad_numbers_are_jumpers no)
		(fp_line
			(start -1.733296 1.549908)
			(end 1.733296 1.549908)
			(stroke
				(width 0.1524)
				(type default)
			)
			(layer "F.SilkS")
		)
		(fp_line
			(start 1.733296 1.549908)
			(end 1.733296 -1.549908)
			(stroke
				(width 0.1524)
				(type default)
			)
			(layer "F.SilkS")
		)
		(fp_line
			(start 0 -0.889)
			(end -0.660908 -1.549908)
			(stroke
				(width 0.1524)
				(type default)
			)
			(layer "F.SilkS")
		)
		(fp_line
			(start -1.733296 -1.549908)
			(end -1.733296 1.549908)
			(stroke
				(width 0.1524)
				(type default)
			)
			(layer "F.SilkS")
		)
		(fp_line
			(start -0.660908 -1.549908)
			(end -1.733296 -1.549908)
			(stroke
				(width 0.1524)
				(type default)
			)
			(layer "F.SilkS")
		)
		(fp_line
			(start 0.660908 -1.549908)
			(end 0 -0.889)
			(stroke
				(width 0.1524)
				(type default)
			)
			(layer "F.SilkS")
		)
		(fp_line
			(start 1.733296 -1.549908)
			(end 0.660908 -1.549908)
			(stroke
				(width 0.1524)
				(type default)
			)
			(layer "F.SilkS")
		)
		(fp_poly
			(pts
				(xy -2.4384 -1.20396) (xy -1.9304 -0.94996) (xy -2.4384 -0.69596)
			)
			(stroke
				(width 0)
				(type default)
			)
			(fill yes)
			(layer "F.SilkS")
		)
		(fp_line
			(start -0.849884 1.549908)
			(end 0.849884 1.549908)
			(stroke
				(width 0.1)
				(type default)
			)
			(layer "F.Fab")
		)
		(fp_line
			(start 0.849884 1.549908)
			(end 0.849884 -1.549908)
			(stroke
				(width 0.1)
				(type default)
			)
			(layer "F.Fab")
		)
		(fp_line
			(start -0.849884 -1.549908)
			(end -0.849884 1.549908)
			(stroke
				(width 0.1)
				(type default)
			)
			(layer "F.Fab")
		)
		(fp_line
			(start 0.849884 -1.549908)
			(end -0.849884 -1.549908)
			(stroke
				(width 0.1)
				(type default)
			)
			(layer "F.Fab")
		)
		(fp_poly
			(pts
				(xy -2.4384 -1.20396) (xy -2.4384 -0.69596) (xy -1.9304 -0.94996)
			)
			(stroke
				(width 0)
				(type default)
			)
			(fill yes)
			(layer "F.Fab")
		)
		(pad "1" smd rect
			(at -1.199896 -0.94996 180)
			(size 0.5588 0.8128)
			(layers "F.Cu" "F.Mask" "F.Paste")
			(net "FM_GPU_HSC_EN")
		)
		(pad "2" smd rect
			(at -1.199896 0 180)
			(size 0.5588 0.8128)
			(layers "F.Cu" "F.Mask" "F.Paste")
			(net "GPU_PRSNT_R")
		)
		(pad "3" smd rect
			(at -1.199896 0.94996 180)
			(size 0.5588 0.8128)
			(layers "F.Cu" "F.Mask" "F.Paste")
			(net "GND")
		)
		(pad "4" smd rect
			(at 1.199896 0.94996 180)
			(size 0.5588 0.8128)
			(layers "F.Cu" "F.Mask" "F.Paste")
			(net "FM_GPU_HSC_EN_BUF_R")
		)
		(pad "5" smd rect
			(at 1.199896 -0.94996 180)
			(size 0.5588 0.8128)
			(layers "F.Cu" "F.Mask" "F.Paste")
			(net "P3V3_AUX")
		)
	)
	(footprint ""
		(layer "F.Cu")
		(at 22.809454 -106.761026 180)
		(property "Reference" "R3668"
			(at 0 0 180)
			(layer "F.SilkS")
			(hide yes)
			(effects
				(font
					(size 1.27 1.27)
				)
			)
		)
		(property "Value" ""
			(at 0 0 180)
			(layer "F.Fab")
			(effects
				(font
					(size 1.27 1.27)
				)
			)
		)
		(duplicate_pad_numbers_are_jumpers no)
		(fp_line
			(start 0.7874 0.4064)
			(end -0.7874 0.4064)
			(stroke
				(width 0.1524)
				(type default)
			)
			(layer "F.SilkS")
		)
		(fp_line
			(start 0.7874 -0.4064)
			(end 0.7874 0.4064)
			(stroke
				(width 0.1524)
				(type default)
			)
			(layer "F.SilkS")
		)
		(fp_line
			(start -0.7874 0.4064)
			(end -0.7874 -0.4064)
			(stroke
				(width 0.1524)
				(type default)
			)
			(layer "F.SilkS")
		)
		(fp_line
			(start -0.7874 -0.4064)
			(end 0.7874 -0.4064)
			(stroke
				(width 0.1524)
				(type default)
			)
			(layer "F.SilkS")
		)
		(fp_line
			(start 0.67945 0.3048)
			(end 0.120396 0.3048)
			(stroke
				(width 0.1)
				(type default)
			)
			(layer "F.Fab")
		)
		(fp_line
			(start 0.67945 -0.3048)
			(end 0.67945 0.3048)
			(stroke
				(width 0.1)
				(type default)
			)
			(layer "F.Fab")
		)
		(fp_line
			(start 0.12065 -0.2794)
			(end 0.12065 -0.3048)
			(stroke
				(width 0.1)
				(type default)
			)
			(layer "F.Fab")
		)
		(fp_line
			(start 0.12065 -0.3048)
			(end 0.67945 -0.3048)
			(stroke
				(width 0.1)
				(type default)
			)
			(layer "F.Fab")
		)
		(fp_line
			(start 0.120396 0.3048)
			(end 0.120396 0.2794)
			(stroke
				(width 0.1)
				(type default)
			)
			(layer "F.Fab")
		)
		(fp_line
			(start 0.120396 0.2794)
			(end -0.12065 0.2794)
			(stroke
				(width 0.1)
				(type default)
			)
			(layer "F.Fab")
		)
		(fp_line
			(start -0.12065 0.3048)
			(end -0.67945 0.3048)
			(stroke
				(width 0.1)
				(type default)
			)
			(layer "F.Fab")
		)
		(fp_line
			(start -0.12065 0.2794)
			(end -0.12065 0.3048)
			(stroke
				(width 0.1)
				(type default)
			)
			(layer "F.Fab")
		)
		(fp_line
			(start -0.12065 -0.2794)
			(end 0.12065 -0.2794)
			(stroke
				(width 0.1)
				(type default)
			)
			(layer "F.Fab")
		)
		(fp_line
			(start -0.12065 -0.305054)
			(end -0.12065 -0.2794)
			(stroke
				(width 0.1)
				(type default)
			)
			(layer "F.Fab")
		)
		(fp_line
			(start -0.67945 0.3048)
			(end -0.67945 -0.305054)
			(stroke
				(width 0.1)
				(type default)
			)
			(layer "F.Fab")
		)
		(fp_line
			(start -0.67945 -0.305054)
			(end -0.12065 -0.305054)
			(stroke
				(width 0.1)
				(type default)
			)
			(layer "F.Fab")
		)
		(pad "1" smd circle
			(at -0.40005 0 180)
			(size 0 0)
			(layers "F.Cu" "F.Mask" "F.Paste")
			(net "ADC128_A1")
		)
		(pad "2" smd circle
			(at 0.40005 0 180)
			(size 0 0)
			(layers "F.Cu" "F.Mask" "F.Paste")
			(net "GND")
		)
	)
)
